(kicad_pcb
	(version 20260206)
	(generator "pcbnew")
	(generator_version "10.0")
	(general
		(thickness 1.6)
		(legacy_teardrops no)
	)
	(paper "A4")
	(title_block
		(title "Bryce Canyon_R.DPB_16317-1_OCP.brd")
		(comment 1 "Bryce Canyon / footprints 324-330 of 2099")
	)
	(layers
		(0 "F.Cu" signal "TOP")
		(4 "In1.Cu" signal "L2GND")
		(6 "In2.Cu" signal "L3")
		(8 "In3.Cu" signal "L4VCC")
		(10 "In4.Cu" signal "L5VCC")
		(12 "In5.Cu" signal "L6")
		(14 "In6.Cu" signal "L7GND")
		(2 "B.Cu" signal "BOTTOM")
		(9 "F.Adhes" user "F.Adhesive")
		(11 "B.Adhes" user "B.Adhesive")
		(13 "F.Paste" user "Package Geometry/Pastemask Top")
		(15 "B.Paste" user "Package Geometry/Pastemask Bottom")
		(5 "F.SilkS" user "Ref Des/Silkscreen Top")
		(7 "B.SilkS" user "Ref Des/Silkscreen Bottom")
		(1 "F.Mask" user "Board Geometry/Soldermask Top")
		(3 "B.Mask" user "Board Geometry/Soldermask Bottom")
		(17 "Dwgs.User" user "User.Drawings")
		(19 "Cmts.User" user "User.Comments")
		(21 "Eco1.User" user "User.Eco1")
		(23 "Eco2.User" user "User.Eco2")
		(25 "Edge.Cuts" user "Board Geometry/Outline")
		(27 "Margin" user)
		(31 "F.CrtYd" user "Package Geometry/Place Bound Top")
		(29 "B.CrtYd" user "Package Geometry/Place Bound Bottom")
		(35 "F.Fab" user "Ref Des/Assembly Top")
		(33 "B.Fab" user "Ref Des/Assembly Bottom")
	)
	(footprint ""
		(layer "F.Cu")
		(at 14.859 -25.527 90)
		(property "Reference" "C351"
			(at 0 0 90)
			(layer "F.SilkS")
			(hide yes)
			(effects
				(font
					(size 1.27 1.27)
				)
			)
		)
		(property "Value" "SCD033U25V2KX-GP"
			(at 1.1811 -2.7051 90)
			(unlocked yes)
			(layer "F.Fab")
			(hide yes)
			(effects
				(font
					(size 1.016 1.016)
					(thickness 0.1524)
				)
			)
		)
		(property "Device Type" "C402H22"
			(at 1.1811 -4.2291 90)
			(unlocked yes)
			(layer "F.Fab")
			(hide yes)
			(effects
				(font
					(size 1.016 1.016)
					(thickness 0.1524)
				)
			)
		)
		(duplicate_pad_numbers_are_jumpers no)
		(fp_rect
			(start -0.4318 0.9525)
			(end 0.4318 -0.9525)
			(stroke
				(width 0)
				(type default)
			)
			(fill no)
			(layer "F.CrtYd")
		)
		(fp_rect
			(start -0.4318 0.9525)
			(end 0.4318 -0.9525)
			(stroke
				(width 0)
				(type default)
			)
			(fill no)
			(layer "F.Fab")
		)
		(pad "1" smd custom
			(at 0 -0.4445 90)
			(size 0.1524 0.1524)
			(layers "F.Cu" "F.Mask" "F.Paste")
			(net "P12V_B")
			(options
				(clearance outline)
				(anchor circle)
			)
			(primitives
				(gr_poly
					(pts
						(arc
							(start 0.3048 -0.2032)
							(mid 0.275042 -0.275042)
							(end 0.2032 -0.3048)
						)
						(arc
							(start -0.2032 -0.3048)
							(mid -0.275042 -0.275042)
							(end -0.3048 -0.2032)
						)
						(arc
							(start -0.3048 0.2032)
							(mid -0.275042 0.275042)
							(end -0.2032 0.3048)
						)
						(arc
							(start 0.2032 0.3048)
							(mid 0.275042 0.275042)
							(end 0.3048 0.2032)
						)
					)
					(width 0)
					(fill yes)
				)
			)
		)
		(pad "2" smd custom
			(at 0 0.4445 90)
			(size 0.1524 0.1524)
			(layers "F.Cu" "F.Mask" "F.Paste")
			(net "SW_HDD_N24")
			(options
				(clearance outline)
				(anchor circle)
			)
			(primitives
				(gr_poly
					(pts
						(arc
							(start 0.3048 -0.2032)
							(mid 0.275042 -0.275042)
							(end 0.2032 -0.3048)
						)
						(arc
							(start -0.2032 -0.3048)
							(mid -0.275042 -0.275042)
							(end -0.3048 -0.2032)
						)
						(arc
							(start -0.3048 0.2032)
							(mid -0.275042 0.275042)
							(end -0.2032 0.3048)
						)
						(arc
							(start 0.2032 0.3048)
							(mid 0.275042 0.275042)
							(end 0.3048 0.2032)
						)
					)
					(width 0)
					(fill yes)
				)
			)
		)
	)
	(footprint ""
		(layer "F.Cu")
		(at 469.519 -24.257)
		(property "Reference" "Q186"
			(at 0 0 0)
			(layer "F.SilkS")
			(hide yes)
			(effects
				(font
					(size 1.27 1.27)
				)
			)
		)
		(property "Value" "AO4407AL-GP"
			(at -3.707384 -1.5367 0)
			(unlocked yes)
			(layer "F.Fab")
			(hide yes)
			(effects
				(font
					(size 1.016 1.016)
					(thickness 0.1524)
				)
			)
		)
		(property "Device Type" "SOIC8H69"
			(at -3.707384 -3.0607 0)
			(unlocked yes)
			(layer "F.Fab")
			(hide yes)
			(effects
				(font
					(size 1.016 1.016)
					(thickness 0.1524)
				)
			)
		)
		(duplicate_pad_numbers_are_jumpers no)
		(fp_line
			(start -2.7432 -1.4224)
			(end -2.7432 1.4224)
			(stroke
				(width 0.1524)
				(type default)
			)
			(layer "F.SilkS")
		)
		(fp_line
			(start -2.7432 1.4224)
			(end -2.6416 1.4224)
			(stroke
				(width 0.1524)
				(type default)
			)
			(layer "F.SilkS")
		)
		(fp_line
			(start -2.7432 1.4224)
			(end 2.1336 1.4224)
			(stroke
				(width 0.1524)
				(type default)
			)
			(layer "F.SilkS")
		)
		(fp_line
			(start -2.7178 -0.508)
			(end -2.1844 -0.0508)
			(stroke
				(width 0.1524)
				(type default)
			)
			(layer "F.SilkS")
		)
		(fp_line
			(start -2.6289 3.4417)
			(end -2.6289 1.4732)
			(stroke
				(width 0.381)
				(type default)
			)
			(layer "F.SilkS")
		)
		(fp_line
			(start -2.1844 -0.0508)
			(end -2.7178 0.508)
			(stroke
				(width 0.1524)
				(type default)
			)
			(layer "F.SilkS")
		)
		(fp_line
			(start 2.1336 -1.4224)
			(end -2.7432 -1.4224)
			(stroke
				(width 0.1524)
				(type default)
			)
			(layer "F.SilkS")
		)
		(fp_line
			(start 2.1336 1.4224)
			(end 2.1336 -1.4224)
			(stroke
				(width 0.1524)
				(type default)
			)
			(layer "F.SilkS")
		)
		(fp_poly
			(pts
				(xy -2.2098 -1.4224) (xy -2.2098 1.4224) (xy 2.2098 1.4224) (xy 2.2098 -1.4224)
			)
			(stroke
				(width 0)
				(type default)
			)
			(fill yes)
			(layer "F.SilkS")
		)
		(fp_rect
			(start -2.450084 2.999994)
			(end 2.450084 -2.999994)
			(stroke
				(width 0)
				(type default)
			)
			(fill no)
			(layer "F.CrtYd")
		)
		(fp_poly
			(pts
				(xy -2.8194 3.6322) (xy -2.8194 -3.6322) (xy 2.8194 -3.6322) (xy 2.8194 1.18364) (xy 2.450084 1.18364)
				(xy 2.450084 -2.999994) (xy -2.450084 -2.999994) (xy -2.450084 2.999994) (xy 2.450084 2.999994)
				(xy 2.450084 1.18618) (xy 2.8194 1.18618) (xy 2.8194 3.6322)
			)
			(stroke
				(width 0)
				(type default)
			)
			(fill no)
			(layer "F.CrtYd")
		)
		(fp_rect
			(start -2.8194 3.6322)
			(end 2.8194 -3.6322)
			(stroke
				(width 0)
				(type default)
			)
			(fill no)
			(layer "F.Fab")
		)
		(pad "1" smd rect
			(at -1.905 2.54)
			(size 0.635 1.651)
			(layers "F.Cu" "F.Mask" "F.Paste")
			(net "P12V_B")
		)
		(pad "2" smd rect
			(at -0.635 2.54)
			(size 0.635 1.651)
			(layers "F.Cu" "F.Mask" "F.Paste")
			(net "P12V_B")
		)
		(pad "3" smd rect
			(at 0.635 2.54)
			(size 0.635 1.651)
			(layers "F.Cu" "F.Mask" "F.Paste")
			(net "P12V_B")
		)
		(pad "4" smd rect
			(at 1.905 2.54)
			(size 0.635 1.651)
			(layers "F.Cu" "F.Mask" "F.Paste")
			(net "SW_HDD_N35")
		)
		(pad "5" smd rect
			(at 1.905 -2.54)
			(size 0.635 1.651)
			(layers "F.Cu" "F.Mask" "F.Paste")
			(net "P12V_HDD35")
		)
		(pad "6" smd rect
			(at 0.635 -2.54)
			(size 0.635 1.651)
			(layers "F.Cu" "F.Mask" "F.Paste")
			(net "P12V_HDD35")
		)
		(pad "7" smd rect
			(at -0.635 -2.54)
			(size 0.635 1.651)
			(layers "F.Cu" "F.Mask" "F.Paste")
			(net "P12V_HDD35")
		)
		(pad "8" smd rect
			(at -1.905 -2.54)
			(size 0.635 1.651)
			(layers "F.Cu" "F.Mask" "F.Paste")
			(net "P12V_HDD35")
		)
	)
	(footprint ""
		(layer "F.Cu")
		(at 396.367 -128.651 180)
		(property "Reference" "R538"
			(at 0 0 180)
			(layer "F.SilkS")
			(hide yes)
			(effects
				(font
					(size 1.27 1.27)
				)
			)
		)
		(property "Value" "1KR2F-3-GP"
			(at 0.064008 -3.993896 180)
			(unlocked yes)
			(layer "F.Fab")
			(hide yes)
			(effects
				(font
					(size 1.016 1.016)
					(thickness 0.1524)
				)
			)
		)
		(property "Device Type" "R402H16"
			(at 0.064008 -5.517896 180)
			(unlocked yes)
			(layer "F.Fab")
			(hide yes)
			(effects
				(font
					(size 1.016 1.016)
					(thickness 0.1524)
				)
			)
		)
		(duplicate_pad_numbers_are_jumpers no)
		(fp_line
			(start 0.508 -0.9398)
			(end -0.508 -0.9398)
			(stroke
				(width 0.1524)
				(type default)
			)
			(layer "F.SilkS")
		)
		(fp_line
			(start -0.508 -0.9398)
			(end -0.508 0.9398)
			(stroke
				(width 0.1524)
				(type default)
			)
			(layer "F.SilkS")
		)
		(fp_rect
			(start -0.508 0.9398)
			(end 0.508 -0.9398)
			(stroke
				(width 0)
				(type default)
			)
			(fill no)
			(layer "F.CrtYd")
		)
		(fp_rect
			(start -0.508 0.9398)
			(end 0.508 -0.9398)
			(stroke
				(width 0)
				(type default)
			)
			(fill no)
			(layer "F.Fab")
		)
		(pad "1" smd custom
			(at 0 -0.4445 180)
			(size 0.1397 0.1397)
			(layers "F.Cu" "F.Mask" "F.Paste")
			(net "P3V3_STBY_B")
			(options
				(clearance outline)
				(anchor circle)
			)
			(primitives
				(gr_poly
					(pts
						(arc
							(start -0.1778 -0.2794)
							(mid -0.249642 -0.249642)
							(end -0.2794 -0.1778)
						)
						(arc
							(start -0.2794 0.1778)
							(mid -0.249642 0.249642)
							(end -0.1778 0.2794)
						)
						(arc
							(start 0.1778 0.2794)
							(mid 0.249642 0.249642)
							(end 0.2794 0.1778)
						)
						(arc
							(start 0.2794 -0.1778)
							(mid 0.249642 -0.249642)
							(end 0.1778 -0.2794)
						)
					)
					(width 0)
					(fill yes)
				)
			)
		)
		(pad "2" smd custom
			(at 0 0.4445 180)
			(size 0.1397 0.1397)
			(layers "F.Cu" "F.Mask" "F.Paste")
			(net "SW_PWR_R_HDD20")
			(options
				(clearance outline)
				(anchor circle)
			)
			(primitives
				(gr_poly
					(pts
						(arc
							(start -0.1778 -0.2794)
							(mid -0.249642 -0.249642)
							(end -0.2794 -0.1778)
						)
						(arc
							(start -0.2794 0.1778)
							(mid -0.249642 0.249642)
							(end -0.1778 0.2794)
						)
						(arc
							(start 0.1778 0.2794)
							(mid 0.249642 0.249642)
							(end 0.2794 0.1778)
						)
						(arc
							(start 0.2794 -0.1778)
							(mid 0.249642 -0.249642)
							(end 0.1778 -0.2794)
						)
					)
					(width 0)
					(fill yes)
				)
			)
		)
	)
	(footprint ""
		(layer "F.Cu")
		(at 280.444448 -353.383342 90)
		(property "Reference" "R1074"
			(at 0 0 90)
			(layer "F.SilkS")
			(hide yes)
			(effects
				(font
					(size 1.27 1.27)
				)
			)
		)
		(property "Value" "4K7R2F-GP"
			(at 0.064008 -3.993896 90)
			(unlocked yes)
			(layer "F.Fab")
			(hide yes)
			(effects
				(font
					(size 1.016 1.016)
					(thickness 0.1524)
				)
			)
		)
		(property "Device Type" "R402H16"
			(at 0.064008 -5.517896 90)
			(unlocked yes)
			(layer "F.Fab")
			(hide yes)
			(effects
				(font
					(size 1.016 1.016)
					(thickness 0.1524)
				)
			)
		)
		(duplicate_pad_numbers_are_jumpers no)
		(fp_line
			(start 0.508 -0.9398)
			(end -0.508 -0.9398)
			(stroke
				(width 0.1524)
				(type default)
			)
			(layer "F.SilkS")
		)
		(fp_line
			(start -0.508 -0.9398)
			(end -0.508 0.9398)
			(stroke
				(width 0.1524)
				(type default)
			)
			(layer "F.SilkS")
		)
		(fp_rect
			(start -0.508 0.9398)
			(end 0.508 -0.9398)
			(stroke
				(width 0)
				(type default)
			)
			(fill no)
			(layer "F.CrtYd")
		)
		(fp_rect
			(start -0.508 0.9398)
			(end 0.508 -0.9398)
			(stroke
				(width 0)
				(type default)
			)
			(fill no)
			(layer "F.Fab")
		)
		(pad "1" smd custom
			(at 0 -0.4445 90)
			(size 0.1397 0.1397)
			(layers "F.Cu" "F.Mask" "F.Paste")
			(net "P3V3_STBY_B")
			(options
				(clearance outline)
				(anchor circle)
			)
			(primitives
				(gr_poly
					(pts
						(arc
							(start -0.1778 -0.2794)
							(mid -0.249642 -0.249642)
							(end -0.2794 -0.1778)
						)
						(arc
							(start -0.2794 0.1778)
							(mid -0.249642 0.249642)
							(end -0.1778 0.2794)
						)
						(arc
							(start 0.1778 0.2794)
							(mid 0.249642 0.249642)
							(end 0.2794 0.1778)
						)
						(arc
							(start 0.2794 -0.1778)
							(mid 0.249642 -0.249642)
							(end 0.1778 -0.2794)
						)
					)
					(width 0)
					(fill yes)
				)
			)
		)
		(pad "2" smd custom
			(at 0 0.4445 90)
			(size 0.1397 0.1397)
			(layers "F.Cu" "F.Mask" "F.Paste")
			(net "MAX31790_B_FAIL")
			(options
				(clearance outline)
				(anchor circle)
			)
			(primitives
				(gr_poly
					(pts
						(arc
							(start -0.1778 -0.2794)
							(mid -0.249642 -0.249642)
							(end -0.2794 -0.1778)
						)
						(arc
							(start -0.2794 0.1778)
							(mid -0.249642 0.249642)
							(end -0.1778 0.2794)
						)
						(arc
							(start 0.1778 0.2794)
							(mid 0.249642 0.249642)
							(end 0.2794 0.1778)
						)
						(arc
							(start 0.2794 -0.1778)
							(mid 0.249642 -0.249642)
							(end 0.1778 -0.2794)
						)
					)
					(width 0)
					(fill yes)
				)
			)
		)
	)
	(footprint ""
		(layer "F.Cu")
		(at 77.851 -265.684 -90)
		(property "Reference" "C60"
			(at 0 0 270)
			(layer "F.SilkS")
			(hide yes)
			(effects
				(font
					(size 1.27 1.27)
				)
			)
		)
		(property "Value" "SC4D7U25V5KX-1-GP"
			(at -0.0762 -6.1214 270)
			(unlocked yes)
			(layer "F.Fab")
			(hide yes)
			(effects
				(font
					(size 1.016 1.016)
					(thickness 0.1524)
				)
			)
		)
		(property "Device Type" "C805H58"
			(at -0.0762 -8.1534 270)
			(unlocked yes)
			(layer "F.Fab")
			(hide yes)
			(effects
				(font
					(size 1.016 1.016)
					(thickness 0.1524)
				)
			)
		)
		(duplicate_pad_numbers_are_jumpers no)
		(fp_line
			(start 0.635 0)
			(end -0.635 0)
			(stroke
				(width 0.508)
				(type default)
			)
			(layer "F.SilkS")
		)
		(fp_rect
			(start -0.9652 1.778)
			(end 0.9652 -1.778)
			(stroke
				(width 0)
				(type default)
			)
			(fill no)
			(layer "F.CrtYd")
		)
		(fp_poly
			(pts
				(xy -0.9652 -1.778) (xy 0.9652 -1.778) (xy 0.9652 1.778) (xy -0.9652 1.778)
			)
			(stroke
				(width 0)
				(type default)
			)
			(fill no)
			(layer "F.Fab")
		)
		(pad "1" smd rect
			(at 0 -0.9652 270)
			(size 1.397 1.143)
			(layers "F.Cu" "F.Mask" "F.Paste")
			(net "P12V_HDD2")
		)
		(pad "2" smd rect
			(at 0 0.9652 270)
			(size 1.397 1.143)
			(layers "F.Cu" "F.Mask" "F.Paste")
			(net "GND")
		)
	)
	(footprint ""
		(layer "F.Cu")
		(at 127.15875 -133.75005 -90)
		(property "Reference" "VIA32"
			(at 0 0 270)
			(layer "F.SilkS")
			(hide yes)
			(effects
				(font
					(size 1.27 1.27)
				)
			)
		)
		(property "Value" "100OHM-8L-2D36MM-L16-GP"
			(at -3.4036 -0.4572 270)
			(unlocked yes)
			(layer "F.Fab")
			(hide yes)
			(effects
				(font
					(size 1.016 1.016)
					(thickness 0.1524)
				)
			)
		)
		(property "Device Type" "VIA-PCIE-4P-427097"
			(at -3.4036 -1.9812 270)
			(unlocked yes)
			(layer "F.Fab")
			(hide yes)
			(effects
				(font
					(size 1.016 1.016)
					(thickness 0.1524)
				)
			)
		)
		(duplicate_pad_numbers_are_jumpers no)
		(fp_rect
			(start -2.1336 0.4826)
			(end 2.1336 -0.4826)
			(stroke
				(width 0)
				(type default)
			)
			(fill no)
			(layer "F.CrtYd")
		)
		(fp_rect
			(start -2.1336 0.4826)
			(end 2.1336 -0.4826)
			(stroke
				(width 0)
				(type default)
			)
			(fill no)
			(layer "F.Fab")
		)
		(pad "1" thru_hole circle
			(at -1.651 0 270)
			(size 0.508 0.508)
			(drill 0.254)
			(layers "*.Cu" "*.Mask")
			(remove_unused_layers no)
			(net "GND")
			(clearance 0.2286)
			(thermal_gap 0.2286)
		)
		(pad "2" thru_hole circle
			(at -0.635 0 270)
			(size 0.508 0.508)
			(drill 0.254)
			(layers "*.Cu" "*.Mask")
			(remove_unused_layers no)
			(net "PHY_DRV_B_TO_SCC_B_15_DP")
			(clearance 0.2286)
			(thermal_gap 0.2286)
		)
		(pad "3" thru_hole circle
			(at 0.635 0 270)
			(size 0.508 0.508)
			(drill 0.254)
			(layers "*.Cu" "*.Mask")
			(remove_unused_layers no)
			(net "PHY_DRV_B_TO_SCC_B_15_DN")
			(clearance 0.2286)
			(thermal_gap 0.2286)
		)
		(pad "4" thru_hole circle
			(at 1.651 0 270)
			(size 0.508 0.508)
			(drill 0.254)
			(layers "*.Cu" "*.Mask")
			(remove_unused_layers no)
			(net "GND")
			(clearance 0.2286)
			(thermal_gap 0.2286)
		)
	)
	(footprint ""
		(layer "F.Cu")
		(at 220.7006 -301.371 180)
		(property "Reference" "R509"
			(at 0 0 180)
			(layer "F.SilkS")
			(hide yes)
			(effects
				(font
					(size 1.27 1.27)
				)
			)
		)
		(property "Value" "10KR2F-2-GP"
			(at 0.064008 -3.993896 180)
			(unlocked yes)
			(layer "F.Fab")
			(hide yes)
			(effects
				(font
					(size 1.016 1.016)
					(thickness 0.1524)
				)
			)
		)
		(property "Device Type" "R402H16"
			(at 0.064008 -5.517896 180)
			(unlocked yes)
			(layer "F.Fab")
			(hide yes)
			(effects
				(font
					(size 1.016 1.016)
					(thickness 0.1524)
				)
			)
		)
		(duplicate_pad_numbers_are_jumpers no)
		(fp_line
			(start 0.508 -0.9398)
			(end -0.508 -0.9398)
			(stroke
				(width 0.1524)
				(type default)
			)
			(layer "F.SilkS")
		)
		(fp_line
			(start -0.508 -0.9398)
			(end -0.508 0.9398)
			(stroke
				(width 0.1524)
				(type default)
			)
			(layer "F.SilkS")
		)
		(fp_rect
			(start -0.508 0.9398)
			(end 0.508 -0.9398)
			(stroke
				(width 0)
				(type default)
			)
			(fill no)
			(layer "F.CrtYd")
		)
		(fp_rect
			(start -0.508 0.9398)
			(end 0.508 -0.9398)
			(stroke
				(width 0)
				(type default)
			)
			(fill no)
			(layer "F.Fab")
		)
		(pad "1" smd custom
			(at 0 -0.4445 180)
			(size 0.1397 0.1397)
			(layers "F.Cu" "F.Mask" "F.Paste")
			(net "P3V3_STBY_A")
			(options
				(clearance outline)
				(anchor circle)
			)
			(primitives
				(gr_poly
					(pts
						(arc
							(start -0.1778 -0.2794)
							(mid -0.249642 -0.249642)
							(end -0.2794 -0.1778)
						)
						(arc
							(start -0.2794 0.1778)
							(mid -0.249642 0.249642)
							(end -0.1778 0.2794)
						)
						(arc
							(start 0.1778 0.2794)
							(mid 0.249642 0.249642)
							(end 0.2794 0.1778)
						)
						(arc
							(start 0.2794 -0.1778)
							(mid 0.249642 -0.249642)
							(end 0.1778 -0.2794)
						)
					)
					(width 0)
					(fill yes)
				)
			)
		)
		(pad "2" smd custom
			(at 0 0.4445 180)
			(size 0.1397 0.1397)
			(layers "F.Cu" "F.Mask" "F.Paste")
			(net "FANTACH_A_OE")
			(options
				(clearance outline)
				(anchor circle)
			)
			(primitives
				(gr_poly
					(pts
						(arc
							(start -0.1778 -0.2794)
							(mid -0.249642 -0.249642)
							(end -0.2794 -0.1778)
						)
						(arc
							(start -0.2794 0.1778)
							(mid -0.249642 0.249642)
							(end -0.1778 0.2794)
						)
						(arc
							(start 0.1778 0.2794)
							(mid 0.249642 0.249642)
							(end 0.2794 0.1778)
						)
						(arc
							(start 0.2794 -0.1778)
							(mid 0.249642 -0.249642)
							(end 0.1778 -0.2794)
						)
					)
					(width 0)
					(fill yes)
				)
			)
		)
	)
)
